(kicad_pcb
	(version 20260206)
	(generator "pcbnew")
	(generator_version "10.0")
	(general
		(thickness 1.6)
		(legacy_teardrops no)
	)
	(paper "A4")
	(title_block
		(title "01162023_DA0F0TEBIF0_F0T_Expander_BD_F_brd_V02_OCP.brd")
		(comment 1 "Grand Teton / footprints 6930-6931 of 9728")
	)
	(layers
		(0 "F.Cu" signal "TOP")
		(4 "In1.Cu" signal "GND")
		(6 "In2.Cu" signal "VCC")
		(8 "In3.Cu" signal "VCC1")
		(10 "In4.Cu" signal "GND1")
		(12 "In5.Cu" signal "IN1")
		(14 "In6.Cu" signal "GND2")
		(16 "In7.Cu" signal "IN2")
		(18 "In8.Cu" signal "GND3")
		(20 "In9.Cu" signal "IN3")
		(22 "In10.Cu" signal "GND4")
		(24 "In11.Cu" signal "IN4")
		(26 "In12.Cu" signal "GND5")
		(28 "In13.Cu" signal "IN5")
		(30 "In14.Cu" signal "GND6")
		(32 "In15.Cu" signal "IN6")
		(34 "In16.Cu" signal "GND7")
		(2 "B.Cu" signal "BOTTOM")
		(9 "F.Adhes" user "F.Adhesive")
		(11 "B.Adhes" user "B.Adhesive")
		(13 "F.Paste" user "Package Geometry/Pastemask Top")
		(15 "B.Paste" user "Package Geometry/Pastemask Bottom")
		(5 "F.SilkS" user "Ref Des/Silkscreen Top")
		(7 "B.SilkS" user "Ref Des/Silkscreen Bottom")
		(1 "F.Mask" user "Board Geometry/Soldermask Top")
		(3 "B.Mask" user "Board Geometry/Soldermask Bottom")
		(17 "Dwgs.User" user "User.Drawings")
		(19 "Cmts.User" user "User.Comments")
		(21 "Eco1.User" user "User.Eco1")
		(23 "Eco2.User" user "User.Eco2")
		(25 "Edge.Cuts" user "Board Geometry/Outline")
		(27 "Margin" user)
		(31 "F.CrtYd" user "Package Geometry/Place Bound Top")
		(29 "B.CrtYd" user "Package Geometry/Place Bound Bottom")
		(35 "F.Fab" user "Ref Des/Assembly Top")
		(33 "B.Fab" user "Ref Des/Assembly Bottom")
	)
	(footprint ""
		(layer "F.Cu")
		(at 361.264962 -26.785062 180)
		(property "Reference" "J42"
			(at 3.984498 -11.185652 90)
			(unlocked yes)
			(layer "F.SilkS")
			(effects
				(font
					(size 0.7874 0.5842)
					(thickness 0.1524)
				)
			)
		)
		(property "Value" ""
			(at 0 0 180)
			(layer "F.Fab")
			(effects
				(font
					(size 1.27 1.27)
				)
			)
		)
		(duplicate_pad_numbers_are_jumpers no)
		(fp_line
			(start 3.150108 12.115038)
			(end 1.529334 12.115038)
			(stroke
				(width 0.1524)
				(type default)
			)
			(layer "F.SilkS")
		)
		(fp_line
			(start 3.074924 12.014962)
			(end 1.632204 12.014962)
			(stroke
				(width 0.1524)
				(type default)
			)
			(layer "F.SilkS")
		)
		(fp_line
			(start 1.632204 -12.014962)
			(end 3.074924 -12.014962)
			(stroke
				(width 0.1524)
				(type default)
			)
			(layer "F.SilkS")
		)
		(fp_line
			(start 1.529334 -12.115038)
			(end 3.150108 -12.115038)
			(stroke
				(width 0.1524)
				(type default)
			)
			(layer "F.SilkS")
		)
		(fp_line
			(start -1.529334 12.115038)
			(end -3.150108 12.115038)
			(stroke
				(width 0.1524)
				(type default)
			)
			(layer "F.SilkS")
		)
		(fp_line
			(start -1.632204 12.014962)
			(end -3.074924 12.014962)
			(stroke
				(width 0.1524)
				(type default)
			)
			(layer "F.SilkS")
		)
		(fp_line
			(start -3.074924 -12.014962)
			(end -1.632204 -12.014962)
			(stroke
				(width 0.1524)
				(type default)
			)
			(layer "F.SilkS")
		)
		(fp_line
			(start -3.150108 -12.115038)
			(end -1.529334 -12.115038)
			(stroke
				(width 0.1524)
				(type default)
			)
			(layer "F.SilkS")
		)
		(fp_poly
			(pts
				(xy 3.463036 -8.736076) (xy 3.885438 -10.00379) (xy 4.730496 -9.158732)
			)
			(stroke
				(width 0)
				(type default)
			)
			(fill yes)
			(layer "F.SilkS")
		)
		(fp_line
			(start 3.074924 12.014962)
			(end -3.074924 12.014962)
			(stroke
				(width 0.1)
				(type default)
			)
			(layer "F.Fab")
		)
		(fp_line
			(start 3.074924 -12.014962)
			(end 3.074924 12.014962)
			(stroke
				(width 0.1)
				(type default)
			)
			(layer "F.Fab")
		)
		(fp_line
			(start -3.074924 12.014962)
			(end -3.074924 -12.014962)
			(stroke
				(width 0.1)
				(type default)
			)
			(layer "F.Fab")
		)
		(fp_line
			(start -3.074924 -12.014962)
			(end 3.074924 -12.014962)
			(stroke
				(width 0.1)
				(type default)
			)
			(layer "F.Fab")
		)
		(fp_poly
			(pts
				(xy 3.348736 -7.994904) (xy 4.543806 -8.592566) (xy 4.543806 -7.397496)
			)
			(stroke
				(width 0)
				(type default)
			)
			(fill yes)
			(layer "F.Fab")
		)
		(pad "" np_thru_hole circle
			(at -1.75006 -9.815068 90)
			(size 1.1176 1.1176)
			(drill 1.1176)
			(layers "*.Cu" "*.Mask")
			(clearance 0.381)
			(thermal_gap 0.381)
		)
		(pad "" np_thru_hole circle
			(at 0 9.815068 90)
			(size 1.1176 1.1176)
			(drill 1.1176)
			(layers "*.Cu" "*.Mask")
			(clearance 0.381)
			(thermal_gap 0.381)
		)
		(pad "A1" smd rect
			(at 2.29997 -7.994904 90)
			(size 0.381 1.27)
			(layers "F.Cu" "F.Mask" "F.Paste")
			(net "GND")
		)
		(pad "A2" smd rect
			(at 2.29997 -7.394956 90)
			(size 0.381 1.27)
			(layers "F.Cu" "F.Mask" "F.Paste")
			(net "GND")
		)
		(pad "A3" smd rect
			(at 2.29997 -6.795008 90)
			(size 0.381 1.27)
			(layers "F.Cu" "F.Mask" "F.Paste")
			(net "GND")
		)
		(pad "A4" smd rect
			(at 2.29997 -6.19506 90)
			(size 0.381 1.27)
			(layers "F.Cu" "F.Mask" "F.Paste")
			(net "GND")
		)
		(pad "A5" smd rect
			(at 2.29997 -5.595112 90)
			(size 0.381 1.27)
			(layers "F.Cu" "F.Mask" "F.Paste")
			(net "GND")
		)
		(pad "A6" smd rect
			(at 2.29997 -4.99491 90)
			(size 0.381 1.27)
			(layers "F.Cu" "F.Mask" "F.Paste")
			(net "GND")
		)
		(pad "A7" smd rect
			(at 2.29997 -4.394962 90)
			(size 0.381 1.27)
			(layers "F.Cu" "F.Mask" "F.Paste")
			(net "SMB_ISO_SSD12_R_SCL")
		)
		(pad "A8" smd rect
			(at 2.29997 -3.795014 90)
			(size 0.381 1.27)
			(layers "F.Cu" "F.Mask" "F.Paste")
			(net "SMB_ISO_SSD12_R_SDA")
		)
		(pad "A9" smd rect
			(at 2.29997 -3.195066 90)
			(size 0.381 1.27)
			(layers "F.Cu" "F.Mask" "F.Paste")
			(net "RST_SMB_SSD12_ISO_R_N")
		)
		(pad "A10" smd rect
			(at 2.29997 -2.595118 90)
			(size 0.381 1.27)
			(layers "F.Cu" "F.Mask" "F.Paste")
			(net "SSD12_LED_ISO_R_N")
		)
		(pad "A11" smd rect
			(at 2.29997 -1.994916 90)
			(size 0.381 1.27)
			(layers "F.Cu" "F.Mask" "F.Paste")
			(net "PU_CLKREQ12")
		)
		(pad "A12" smd rect
			(at 2.29997 -1.394968 90)
			(size 0.381 1.27)
			(layers "F.Cu" "F.Mask" "F.Paste")
			(net "PRSNT_SSD12_N")
		)
		(pad "A13" smd rect
			(at 2.29997 -0.79502 90)
			(size 0.381 1.27)
			(layers "F.Cu" "F.Mask" "F.Paste")
			(net "GND")
		)
		(pad "A14" smd rect
			(at 2.29997 -0.195072 90)
			(size 0.381 1.27)
			(layers "F.Cu" "F.Mask" "F.Paste")
			(net "Net_8477")
		)
		(pad "A15" smd rect
			(at 2.29997 0.404876 90)
			(size 0.381 1.27)
			(layers "F.Cu" "F.Mask" "F.Paste")
			(net "Net_8476")
		)
		(pad "A16" smd rect
			(at 2.29997 1.005078 90)
			(size 0.381 1.27)
			(layers "F.Cu" "F.Mask" "F.Paste")
			(net "GND")
		)
		(pad "A17" smd rect
			(at 2.29997 1.605026 90)
			(size 0.381 1.27)
			(layers "F.Cu" "F.Mask" "F.Paste")
			(net "P5E_PEX3_STN2_RX_DN<44>")
		)
		(pad "A18" smd rect
			(at 2.29997 2.204974 90)
			(size 0.381 1.27)
			(layers "F.Cu" "F.Mask" "F.Paste")
			(net "P5E_PEX3_STN2_RX_DP<44>")
		)
		(pad "A19" smd rect
			(at 2.29997 2.804922 90)
			(size 0.381 1.27)
			(layers "F.Cu" "F.Mask" "F.Paste")
			(net "GND")
		)
		(pad "A20" smd rect
			(at 2.29997 3.405124 90)
			(size 0.381 1.27)
			(layers "F.Cu" "F.Mask" "F.Paste")
			(net "P5E_PEX3_STN2_RX_DN<45>")
		)
		(pad "A21" smd rect
			(at 2.29997 4.005072 90)
			(size 0.381 1.27)
			(layers "F.Cu" "F.Mask" "F.Paste")
			(net "P5E_PEX3_STN2_RX_DP<45>")
		)
		(pad "A22" smd rect
			(at 2.29997 4.60502 90)
			(size 0.381 1.27)
			(layers "F.Cu" "F.Mask" "F.Paste")
			(net "GND")
		)
		(pad "A23" smd rect
			(at 2.29997 5.204968 90)
			(size 0.381 1.27)
			(layers "F.Cu" "F.Mask" "F.Paste")
			(net "P5E_PEX3_STN2_RX_DN<46>")
		)
		(pad "A24" smd rect
			(at 2.29997 5.804916 90)
			(size 0.381 1.27)
			(layers "F.Cu" "F.Mask" "F.Paste")
			(net "P5E_PEX3_STN2_RX_DP<46>")
		)
		(pad "A25" smd rect
			(at 2.29997 6.405118 90)
			(size 0.381 1.27)
			(layers "F.Cu" "F.Mask" "F.Paste")
			(net "GND")
		)
		(pad "A26" smd rect
			(at 2.29997 7.005066 90)
			(size 0.381 1.27)
			(layers "F.Cu" "F.Mask" "F.Paste")
			(net "P5E_PEX3_STN2_RX_DN<47>")
		)
		(pad "A27" smd rect
			(at 2.29997 7.605014 90)
			(size 0.381 1.27)
			(layers "F.Cu" "F.Mask" "F.Paste")
			(net "P5E_PEX3_STN2_RX_DP<47>")
		)
		(pad "A28" smd rect
			(at 2.29997 8.204962 90)
			(size 0.381 1.27)
			(layers "F.Cu" "F.Mask" "F.Paste")
			(net "GND")
		)
		(pad "B1" smd rect
			(at -2.29997 -7.994904 90)
			(size 0.381 1.27)
			(layers "F.Cu" "F.Mask" "F.Paste")
			(net "P12V_SSD12")
		)
		(pad "B2" smd rect
			(at -2.29997 -7.394956 90)
			(size 0.381 1.27)
			(layers "F.Cu" "F.Mask" "F.Paste")
			(net "P12V_SSD12")
		)
		(pad "B3" smd rect
			(at -2.29997 -6.795008 90)
			(size 0.381 1.27)
			(layers "F.Cu" "F.Mask" "F.Paste")
			(net "P12V_SSD12")
		)
		(pad "B4" smd rect
			(at -2.29997 -6.19506 90)
			(size 0.381 1.27)
			(layers "F.Cu" "F.Mask" "F.Paste")
			(net "P12V_SSD12")
		)
		(pad "B5" smd rect
			(at -2.29997 -5.595112 90)
			(size 0.381 1.27)
			(layers "F.Cu" "F.Mask" "F.Paste")
			(net "P12V_SSD12")
		)
		(pad "B6" smd rect
			(at -2.29997 -4.99491 90)
			(size 0.381 1.27)
			(layers "F.Cu" "F.Mask" "F.Paste")
			(net "P12V_SSD12")
		)
		(pad "B7" smd rect
			(at -2.29997 -4.394962 90)
			(size 0.381 1.27)
			(layers "F.Cu" "F.Mask" "F.Paste")
			(net "Net_8478")
		)
		(pad "B8" smd rect
			(at -2.29997 -3.795014 90)
			(size 0.381 1.27)
			(layers "F.Cu" "F.Mask" "F.Paste")
			(net "Net_8475")
		)
		(pad "B9" smd rect
			(at -2.29997 -3.195066 90)
			(size 0.381 1.27)
			(layers "F.Cu" "F.Mask" "F.Paste")
			(net "DUALPORT_N_SSD12")
		)
		(pad "B10" smd rect
			(at -2.29997 -2.595118 90)
			(size 0.381 1.27)
			(layers "F.Cu" "F.Mask" "F.Paste")
			(net "RST_SSD12_PERST_R_N")
		)
		(pad "B11" smd rect
			(at -2.29997 -1.994916 90)
			(size 0.381 1.27)
			(layers "F.Cu" "F.Mask" "F.Paste")
			(net "P3V3_SSD12")
		)
		(pad "B12" smd rect
			(at -2.29997 -1.394968 90)
			(size 0.381 1.27)
			(layers "F.Cu" "F.Mask" "F.Paste")
			(net "SSD12_PWRDIS_R")
		)
		(pad "B13" smd rect
			(at -2.29997 -0.79502 90)
			(size 0.381 1.27)
			(layers "F.Cu" "F.Mask" "F.Paste")
			(net "GND")
		)
		(pad "B14" smd rect
			(at -2.29997 -0.195072 90)
			(size 0.381 1.27)
			(layers "F.Cu" "F.Mask" "F.Paste")
			(net "CLK_100M_DB800ZL_SSD12_R_DN")
		)
		(pad "B15" smd rect
			(at -2.29997 0.404876 90)
			(size 0.381 1.27)
			(layers "F.Cu" "F.Mask" "F.Paste")
			(net "CLK_100M_DB800ZL_SSD12_R_DP")
		)
		(pad "B16" smd rect
			(at -2.29997 1.005078 90)
			(size 0.381 1.27)
			(layers "F.Cu" "F.Mask" "F.Paste")
			(net "GND")
		)
		(pad "B17" smd rect
			(at -2.29997 1.605026 90)
			(size 0.381 1.27)
			(layers "F.Cu" "F.Mask" "F.Paste")
			(net "P5E_PEX3_STN2_TX_C_DN<44>")
		)
		(pad "B18" smd rect
			(at -2.29997 2.204974 90)
			(size 0.381 1.27)
			(layers "F.Cu" "F.Mask" "F.Paste")
			(net "P5E_PEX3_STN2_TX_C_DP<44>")
		)
		(pad "B19" smd rect
			(at -2.29997 2.804922 90)
			(size 0.381 1.27)
			(layers "F.Cu" "F.Mask" "F.Paste")
			(net "GND")
		)
		(pad "B20" smd rect
			(at -2.29997 3.405124 90)
			(size 0.381 1.27)
			(layers "F.Cu" "F.Mask" "F.Paste")
			(net "P5E_PEX3_STN2_TX_C_DN<45>")
		)
		(pad "B21" smd rect
			(at -2.29997 4.005072 90)
			(size 0.381 1.27)
			(layers "F.Cu" "F.Mask" "F.Paste")
			(net "P5E_PEX3_STN2_TX_C_DP<45>")
		)
		(pad "B22" smd rect
			(at -2.29997 4.60502 90)
			(size 0.381 1.27)
			(layers "F.Cu" "F.Mask" "F.Paste")
			(net "GND")
		)
		(pad "B23" smd rect
			(at -2.29997 5.204968 90)
			(size 0.381 1.27)
			(layers "F.Cu" "F.Mask" "F.Paste")
			(net "P5E_PEX3_STN2_TX_C_DN<46>")
		)
		(pad "B24" smd rect
			(at -2.29997 5.804916 90)
			(size 0.381 1.27)
			(layers "F.Cu" "F.Mask" "F.Paste")
			(net "P5E_PEX3_STN2_TX_C_DP<46>")
		)
		(pad "B25" smd rect
			(at -2.29997 6.405118 90)
			(size 0.381 1.27)
			(layers "F.Cu" "F.Mask" "F.Paste")
			(net "GND")
		)
		(pad "B26" smd rect
			(at -2.29997 7.005066 90)
			(size 0.381 1.27)
			(layers "F.Cu" "F.Mask" "F.Paste")
			(net "P5E_PEX3_STN2_TX_C_DN<47>")
		)
		(pad "B27" smd rect
			(at -2.29997 7.605014 90)
			(size 0.381 1.27)
			(layers "F.Cu" "F.Mask" "F.Paste")
			(net "P5E_PEX3_STN2_TX_C_DP<47>")
		)
		(pad "B28" smd rect
			(at -2.29997 8.204962 90)
			(size 0.381 1.27)
			(layers "F.Cu" "F.Mask" "F.Paste")
			(net "GND")
		)
		(pad "G1" thru_hole oval
			(at 0 -11.364976 90)
			(size 1.6256 3.4798)
			(drill oval 1.1176 2.4638)
			(layers "*.Cu" "*.Mask")
			(remove_unused_layers no)
			(net "GND")
			(clearance 0.127)
			(thermal_gap 0.127)
		)
		(pad "G2" thru_hole oval
			(at 0 11.364976 90)
			(size 1.6256 3.4798)
			(drill oval 1.1176 2.4638)
			(layers "*.Cu" "*.Mask")
			(remove_unused_layers no)
			(net "GND")
			(clearance 0.127)
			(thermal_gap 0.127)
		)
		(zone
			(layer "F.Cu")
			(hatch none 0.5)
			(connect_pads
				(clearance 0)
			)
			(min_thickness 0.25)
			(keepout
				(tracks not_allowed)
				(vias allowed)
				(pads allowed)
				(copperpour not_allowed)
				(footprints allowed)
			)
			(placement
				(enabled no)
				(sheetname "")
			)
			(fill
				(thermal_gap 0.5)
				(thermal_bridge_width 0.5)
				(island_removal_mode 0)
			)
			(polygon
				(pts
					(xy 362.644944 -38.850062) (xy 359.894886 -38.850062) (xy 359.894886 -35.900106) (xy 362.644944 -35.900106)
				)
			)
		)
		(zone
			(layer "F.Cu")
			(hatch none 0.5)
			(connect_pads
				(clearance 0)
			)
			(min_thickness 0.25)
			(keepout
				(tracks not_allowed)
				(vias allowed)
				(pads allowed)
				(copperpour not_allowed)
				(footprints allowed)
			)
			(placement
				(enabled no)
				(sheetname "")
			)
			(fill
				(thermal_gap 0.5)
				(thermal_bridge_width 0.5)
				(island_removal_mode 0)
			)
			(polygon
				(pts
					(xy 363.715046 -17.670018) (xy 359.88498 -17.670018) (xy 359.88498 -14.720062) (xy 363.715046 -14.720062)
				)
			)
		)
		(zone
			(layers "F.Cu" "B.Cu" "In1.Cu" "In2.Cu" "In3.Cu" "In4.Cu" "In5.Cu" "In6.Cu"
				"In7.Cu" "In8.Cu" "In9.Cu" "In10.Cu" "In11.Cu" "In12.Cu" "In13.Cu" "In14.Cu"
				"In15.Cu" "In16.Cu"
			)
			(hatch none 0.5)
			(connect_pads
				(clearance 0)
			)
			(min_thickness 0.25)
			(keepout
				(tracks not_allowed)
				(vias allowed)
				(pads allowed)
				(copperpour not_allowed)
				(footprints allowed)
			)
			(placement
				(enabled no)
				(sheetname "")
			)
			(fill
				(thermal_gap 0.5)
				(thermal_bridge_width 0.5)
				(island_removal_mode 0)
			)
			(polygon
				(pts
					(arc
						(start 362.230162 -36.60013)
						(mid 360.299762 -36.60013)
						(end 362.230162 -36.60013)
					)
				)
			)
		)
		(zone
			(layers "F.Cu" "B.Cu" "In1.Cu" "In2.Cu" "In3.Cu" "In4.Cu" "In5.Cu" "In6.Cu"
				"In7.Cu" "In8.Cu" "In9.Cu" "In10.Cu" "In11.Cu" "In12.Cu" "In13.Cu" "In14.Cu"
				"In15.Cu" "In16.Cu"
			)
			(hatch none 0.5)
			(connect_pads
				(clearance 0)
			)
			(min_thickness 0.25)
			(keepout
				(tracks not_allowed)
				(vias allowed)
				(pads allowed)
				(copperpour not_allowed)
				(footprints allowed)
			)
			(placement
				(enabled no)
				(sheetname "")
			)
			(fill
				(thermal_gap 0.5)
				(thermal_bridge_width 0.5)
				(island_removal_mode 0)
			)
			(polygon
				(pts
					(arc
						(start 363.980222 -16.969994)
						(mid 362.049822 -16.969994)
						(end 363.980222 -16.969994)
					)
				)
			)
		)
	)
	(footprint ""
		(layer "F.Cu")
		(at 390.73074 -356.244906 90)
		(property "Reference" "C743"
			(at 0 0 90)
			(layer "F.SilkS")
			(hide yes)
			(effects
				(font
					(size 1.27 1.27)
				)
			)
		)
		(property "Value" ""
			(at 0 0 90)
			(layer "F.Fab")
			(effects
				(font
					(size 1.27 1.27)
				)
			)
		)
		(duplicate_pad_numbers_are_jumpers no)
		(fp_line
			(start 0.299974 -0.150114)
			(end 0.299974 0.150114)
			(stroke
				(width 0.1)
				(type default)
			)
			(layer "F.Fab")
		)
		(fp_line
			(start -0.299974 -0.150114)
			(end 0.299974 -0.150114)
			(stroke
				(width 0.1)
				(type default)
			)
			(layer "F.Fab")
		)
		(fp_line
			(start 0.299974 0.150114)
			(end -0.299974 0.150114)
			(stroke
				(width 0.1)
				(type default)
			)
			(layer "F.Fab")
		)
		(fp_line
			(start -0.299974 0.150114)
			(end -0.299974 -0.150114)
			(stroke
				(width 0.1)
				(type default)
			)
			(layer "F.Fab")
		)
		(pad "1" smd rect
			(at -0.2667 0 90)
			(size 0.3048 0.381)
			(layers "F.Cu" "F.Mask" "F.Paste")
			(net "P5E_PEX3_STN5_TX_DN<89>")
		)
		(pad "2" smd rect
			(at 0.2667 0 90)
			(size 0.3048 0.381)
			(layers "F.Cu" "F.Mask" "F.Paste")
			(net "P5E_PEX3_STN5_TX_C_DN<89>")
		)
	)
)
